(kicad_pcb
	(version 20260206)
	(generator "pcbnew")
	(generator_version "10.0")
	(general
		(thickness 1.6)
		(legacy_teardrops no)
	)
	(paper "A4")
	(title_block
		(title "Bryce Canyon_R.DPB_16317-1_OCP.brd")
		(comment 1 "Bryce Canyon / footprints 1619-1625 of 2099")
	)
	(layers
		(0 "F.Cu" signal "TOP")
		(4 "In1.Cu" signal "L2GND")
		(6 "In2.Cu" signal "L3")
		(8 "In3.Cu" signal "L4VCC")
		(10 "In4.Cu" signal "L5VCC")
		(12 "In5.Cu" signal "L6")
		(14 "In6.Cu" signal "L7GND")
		(2 "B.Cu" signal "BOTTOM")
		(9 "F.Adhes" user "F.Adhesive")
		(11 "B.Adhes" user "B.Adhesive")
		(13 "F.Paste" user "Package Geometry/Pastemask Top")
		(15 "B.Paste" user "Package Geometry/Pastemask Bottom")
		(5 "F.SilkS" user "Ref Des/Silkscreen Top")
		(7 "B.SilkS" user "Ref Des/Silkscreen Bottom")
		(1 "F.Mask" user "Board Geometry/Soldermask Top")
		(3 "B.Mask" user "Board Geometry/Soldermask Bottom")
		(17 "Dwgs.User" user "User.Drawings")
		(19 "Cmts.User" user "User.Comments")
		(21 "Eco1.User" user "User.Eco1")
		(23 "Eco2.User" user "User.Eco2")
		(25 "Edge.Cuts" user "Board Geometry/Outline")
		(27 "Margin" user)
		(31 "F.CrtYd" user "Package Geometry/Place Bound Top")
		(29 "B.CrtYd" user "Package Geometry/Place Bound Bottom")
		(35 "F.Fab" user "Ref Des/Assembly Top")
		(33 "B.Fab" user "Ref Des/Assembly Bottom")
	)
	(footprint ""
		(layer "F.Cu")
		(at 263.114536 -216.33307 -90)
		(property "Reference" "R163"
			(at 0 0 270)
			(layer "F.SilkS")
			(hide yes)
			(effects
				(font
					(size 1.27 1.27)
				)
			)
		)
		(property "Value" "4K7R2F-GP"
			(at 0.064008 -3.993896 270)
			(unlocked yes)
			(layer "F.Fab")
			(hide yes)
			(effects
				(font
					(size 1.016 1.016)
					(thickness 0.1524)
				)
			)
		)
		(property "Device Type" "R402H16"
			(at 0.064008 -5.517896 270)
			(unlocked yes)
			(layer "F.Fab")
			(hide yes)
			(effects
				(font
					(size 1.016 1.016)
					(thickness 0.1524)
				)
			)
		)
		(duplicate_pad_numbers_are_jumpers no)
		(fp_line
			(start -0.508 -0.9398)
			(end -0.508 0.9398)
			(stroke
				(width 0.1524)
				(type default)
			)
			(layer "F.SilkS")
		)
		(fp_line
			(start 0.508 -0.9398)
			(end -0.508 -0.9398)
			(stroke
				(width 0.1524)
				(type default)
			)
			(layer "F.SilkS")
		)
		(fp_rect
			(start -0.508 0.9398)
			(end 0.508 -0.9398)
			(stroke
				(width 0)
				(type default)
			)
			(fill no)
			(layer "F.CrtYd")
		)
		(fp_rect
			(start -0.508 0.9398)
			(end 0.508 -0.9398)
			(stroke
				(width 0)
				(type default)
			)
			(fill no)
			(layer "F.Fab")
		)
		(pad "1" smd custom
			(at 0 -0.4445 270)
			(size 0.1397 0.1397)
			(layers "F.Cu" "F.Mask" "F.Paste")
			(net "P3V3_STBY_B")
			(options
				(clearance outline)
				(anchor circle)
			)
			(primitives
				(gr_poly
					(pts
						(arc
							(start -0.1778 -0.2794)
							(mid -0.249642 -0.249642)
							(end -0.2794 -0.1778)
						)
						(arc
							(start -0.2794 0.1778)
							(mid -0.249642 0.249642)
							(end -0.1778 0.2794)
						)
						(arc
							(start 0.1778 0.2794)
							(mid 0.249642 0.249642)
							(end 0.2794 0.1778)
						)
						(arc
							(start 0.2794 -0.1778)
							(mid 0.249642 -0.249642)
							(end 0.1778 -0.2794)
						)
					)
					(width 0)
					(fill yes)
				)
			)
		)
		(pad "2" smd custom
			(at 0 0.4445 270)
			(size 0.1397 0.1397)
			(layers "F.Cu" "F.Mask" "F.Paste")
			(net "VOL_SEN_ADDR1")
			(options
				(clearance outline)
				(anchor circle)
			)
			(primitives
				(gr_poly
					(pts
						(arc
							(start -0.1778 -0.2794)
							(mid -0.249642 -0.249642)
							(end -0.2794 -0.1778)
						)
						(arc
							(start -0.2794 0.1778)
							(mid -0.249642 0.249642)
							(end -0.1778 0.2794)
						)
						(arc
							(start 0.1778 0.2794)
							(mid 0.249642 0.249642)
							(end 0.2794 0.1778)
						)
						(arc
							(start 0.2794 -0.1778)
							(mid 0.249642 -0.249642)
							(end 0.1778 -0.2794)
						)
					)
					(width 0)
					(fill yes)
				)
			)
		)
	)
	(footprint ""
		(layer "F.Cu")
		(at 368.427 -246.761 180)
		(property "Reference" "R280"
			(at 0 0 180)
			(layer "F.SilkS")
			(hide yes)
			(effects
				(font
					(size 1.27 1.27)
				)
			)
		)
		(property "Value" "4K7R2J-2-GP"
			(at 0.064008 -3.993896 180)
			(unlocked yes)
			(layer "F.Fab")
			(hide yes)
			(effects
				(font
					(size 1.016 1.016)
					(thickness 0.1524)
				)
			)
		)
		(property "Device Type" "R402H16"
			(at 0.064008 -5.517896 180)
			(unlocked yes)
			(layer "F.Fab")
			(hide yes)
			(effects
				(font
					(size 1.016 1.016)
					(thickness 0.1524)
				)
			)
		)
		(duplicate_pad_numbers_are_jumpers no)
		(fp_line
			(start 0.508 -0.9398)
			(end -0.508 -0.9398)
			(stroke
				(width 0.1524)
				(type default)
			)
			(layer "F.SilkS")
		)
		(fp_line
			(start -0.508 -0.9398)
			(end -0.508 0.9398)
			(stroke
				(width 0.1524)
				(type default)
			)
			(layer "F.SilkS")
		)
		(fp_rect
			(start -0.508 0.9398)
			(end 0.508 -0.9398)
			(stroke
				(width 0)
				(type default)
			)
			(fill no)
			(layer "F.CrtYd")
		)
		(fp_rect
			(start -0.508 0.9398)
			(end 0.508 -0.9398)
			(stroke
				(width 0)
				(type default)
			)
			(fill no)
			(layer "F.Fab")
		)
		(pad "1" smd custom
			(at 0 -0.4445 180)
			(size 0.1397 0.1397)
			(layers "F.Cu" "F.Mask" "F.Paste")
			(net "P12V_B")
			(options
				(clearance outline)
				(anchor circle)
			)
			(primitives
				(gr_poly
					(pts
						(arc
							(start -0.1778 -0.2794)
							(mid -0.249642 -0.249642)
							(end -0.2794 -0.1778)
						)
						(arc
							(start -0.2794 0.1778)
							(mid -0.249642 0.249642)
							(end -0.1778 0.2794)
						)
						(arc
							(start 0.1778 0.2794)
							(mid 0.249642 0.249642)
							(end 0.2794 0.1778)
						)
						(arc
							(start 0.2794 -0.1778)
							(mid 0.249642 -0.249642)
							(end 0.1778 -0.2794)
						)
					)
					(width 0)
					(fill yes)
				)
			)
		)
		(pad "2" smd custom
			(at 0 0.4445 180)
			(size 0.1397 0.1397)
			(layers "F.Cu" "F.Mask" "F.Paste")
			(net "SW_HDD_R7")
			(options
				(clearance outline)
				(anchor circle)
			)
			(primitives
				(gr_poly
					(pts
						(arc
							(start -0.1778 -0.2794)
							(mid -0.249642 -0.249642)
							(end -0.2794 -0.1778)
						)
						(arc
							(start -0.2794 0.1778)
							(mid -0.249642 0.249642)
							(end -0.1778 0.2794)
						)
						(arc
							(start 0.1778 0.2794)
							(mid 0.249642 0.249642)
							(end 0.2794 0.1778)
						)
						(arc
							(start 0.2794 -0.1778)
							(mid 0.249642 -0.249642)
							(end 0.1778 -0.2794)
						)
					)
					(width 0)
					(fill yes)
				)
			)
		)
	)
	(footprint ""
		(layer "F.Cu")
		(at 205.8416 -145.288)
		(property "Reference" "TC1"
			(at 0 0 0)
			(layer "F.SilkS")
			(hide yes)
			(effects
				(font
					(size 1.27 1.27)
				)
			)
		)
		(property "Value" "SE270U16VM-8-GP"
			(at -4.5974 -2.54 0)
			(unlocked yes)
			(layer "F.Fab")
			(hide yes)
			(effects
				(font
					(size 1.016 1.016)
					(thickness 0.1524)
				)
			)
		)
		(property "Device Type" "SE361416H394"
			(at -4.5974 -4.064 0)
			(unlocked yes)
			(layer "F.Fab")
			(hide yes)
			(effects
				(font
					(size 1.016 1.016)
					(thickness 0.1524)
				)
			)
		)
		(duplicate_pad_numbers_are_jumpers no)
		(fp_line
			(start -3.556 -3.4163)
			(end -2.3622 -4.6101)
			(stroke
				(width 0.1524)
				(type default)
			)
			(layer "F.SilkS")
		)
		(fp_line
			(start -3.556 4.6101)
			(end -3.556 -3.4163)
			(stroke
				(width 0.1524)
				(type default)
			)
			(layer "F.SilkS")
		)
		(fp_line
			(start -2.3622 -4.6101)
			(end 2.3622 -4.6101)
			(stroke
				(width 0.1524)
				(type default)
			)
			(layer "F.SilkS")
		)
		(fp_line
			(start 2.3622 -4.6101)
			(end 3.556 -3.4163)
			(stroke
				(width 0.1524)
				(type default)
			)
			(layer "F.SilkS")
		)
		(fp_line
			(start 3.556 -3.4163)
			(end 3.556 4.6101)
			(stroke
				(width 0.1524)
				(type default)
			)
			(layer "F.SilkS")
		)
		(fp_line
			(start 3.556 4.6101)
			(end -3.556 4.6101)
			(stroke
				(width 0.1524)
				(type default)
			)
			(layer "F.SilkS")
		)
		(fp_rect
			(start -3.302 3.6449)
			(end 3.302 -3.6449)
			(stroke
				(width 0)
				(type default)
			)
			(fill no)
			(layer "F.CrtYd")
		)
		(fp_poly
			(pts
				(xy 3.81 4.6863) (xy 3.81 -3.4925) (xy 3.302 -3.4925) (xy 3.302 3.6449) (xy -3.302 3.6449) (xy -3.302 -3.6449)
				(xy 3.302 -3.6449) (xy 3.302 -3.5052) (xy 3.81 -3.5052) (xy 3.81 -4.6863) (xy -3.81 -4.6863) (xy -3.81 4.6863)
			)
			(stroke
				(width 0)
				(type default)
			)
			(fill no)
			(layer "F.CrtYd")
		)
		(fp_rect
			(start -3.81 4.6863)
			(end 3.81 -4.6863)
			(stroke
				(width 0)
				(type default)
			)
			(fill no)
			(layer "F.Fab")
		)
		(pad "1" smd rect
			(at 0 -2.574036)
			(size 1.4224 3.556)
			(layers "F.Cu" "F.Mask" "F.Paste")
			(net "P12V_B")
		)
		(pad "2" smd rect
			(at 0 2.574036)
			(size 1.4224 3.556)
			(layers "F.Cu" "F.Mask" "F.Paste")
			(net "GND")
		)
	)
	(footprint ""
		(layer "F.Cu")
		(at 375.543826 -217.413586 -90)
		(property "Reference" "R274"
			(at 0 0 270)
			(layer "F.SilkS")
			(hide yes)
			(effects
				(font
					(size 1.27 1.27)
				)
			)
		)
		(property "Value" "4K7R2F-GP"
			(at 0.064008 -3.993896 270)
			(unlocked yes)
			(layer "F.Fab")
			(hide yes)
			(effects
				(font
					(size 1.016 1.016)
					(thickness 0.1524)
				)
			)
		)
		(property "Device Type" "R402H16"
			(at 0.064008 -5.517896 270)
			(unlocked yes)
			(layer "F.Fab")
			(hide yes)
			(effects
				(font
					(size 1.016 1.016)
					(thickness 0.1524)
				)
			)
		)
		(duplicate_pad_numbers_are_jumpers no)
		(fp_line
			(start -0.508 -0.9398)
			(end -0.508 0.9398)
			(stroke
				(width 0.1524)
				(type default)
			)
			(layer "F.SilkS")
		)
		(fp_line
			(start 0.508 -0.9398)
			(end -0.508 -0.9398)
			(stroke
				(width 0.1524)
				(type default)
			)
			(layer "F.SilkS")
		)
		(fp_rect
			(start -0.508 0.9398)
			(end 0.508 -0.9398)
			(stroke
				(width 0)
				(type default)
			)
			(fill no)
			(layer "F.CrtYd")
		)
		(fp_rect
			(start -0.508 0.9398)
			(end 0.508 -0.9398)
			(stroke
				(width 0)
				(type default)
			)
			(fill no)
			(layer "F.Fab")
		)
		(pad "1" smd custom
			(at 0 -0.4445 270)
			(size 0.1397 0.1397)
			(layers "F.Cu" "F.Mask" "F.Paste")
			(net "DRIVE_B_8_FLT_LED")
			(options
				(clearance outline)
				(anchor circle)
			)
			(primitives
				(gr_poly
					(pts
						(arc
							(start -0.1778 -0.2794)
							(mid -0.249642 -0.249642)
							(end -0.2794 -0.1778)
						)
						(arc
							(start -0.2794 0.1778)
							(mid -0.249642 0.249642)
							(end -0.1778 0.2794)
						)
						(arc
							(start 0.1778 0.2794)
							(mid 0.249642 0.249642)
							(end 0.2794 0.1778)
						)
						(arc
							(start 0.2794 -0.1778)
							(mid 0.249642 -0.249642)
							(end 0.1778 -0.2794)
						)
					)
					(width 0)
					(fill yes)
				)
			)
		)
		(pad "2" smd custom
			(at 0 0.4445 270)
			(size 0.1397 0.1397)
			(layers "F.Cu" "F.Mask" "F.Paste")
			(net "GND")
			(options
				(clearance outline)
				(anchor circle)
			)
			(primitives
				(gr_poly
					(pts
						(arc
							(start -0.1778 -0.2794)
							(mid -0.249642 -0.249642)
							(end -0.2794 -0.1778)
						)
						(arc
							(start -0.2794 0.1778)
							(mid -0.249642 0.249642)
							(end -0.1778 0.2794)
						)
						(arc
							(start 0.1778 0.2794)
							(mid 0.249642 0.249642)
							(end 0.2794 0.1778)
						)
						(arc
							(start 0.2794 -0.1778)
							(mid 0.249642 -0.249642)
							(end 0.1778 -0.2794)
						)
					)
					(width 0)
					(fill yes)
				)
			)
		)
	)
	(footprint ""
		(layer "F.Cu")
		(at 371.293644 -99.860354 90)
		(property "Reference" "Q261"
			(at 0 0 90)
			(layer "F.SilkS")
			(hide yes)
			(effects
				(font
					(size 1.27 1.27)
				)
			)
		)
		(property "Value" "SSM3K324R-GP"
			(at 0.127 -8.9662 90)
			(unlocked yes)
			(layer "F.Fab")
			(hide yes)
			(effects
				(font
					(size 1.016 1.016)
					(thickness 0.1524)
				)
			)
		)
		(property "Device Type" "SOT23DGS2D4H35"
			(at 0.127 -10.4902 90)
			(unlocked yes)
			(layer "F.Fab")
			(hide yes)
			(effects
				(font
					(size 1.016 1.016)
					(thickness 0.1524)
				)
			)
		)
		(duplicate_pad_numbers_are_jumpers no)
		(fp_line
			(start 1.651 -1.778)
			(end -1.651 -1.778)
			(stroke
				(width 0.1524)
				(type default)
			)
			(layer "F.SilkS")
		)
		(fp_line
			(start -1.651 -1.778)
			(end -1.651 1.778)
			(stroke
				(width 0.1524)
				(type default)
			)
			(layer "F.SilkS")
		)
		(fp_line
			(start 1.651 1.778)
			(end 1.651 -1.778)
			(stroke
				(width 0.1524)
				(type default)
			)
			(layer "F.SilkS")
		)
		(fp_line
			(start -1.651 1.778)
			(end 1.651 1.778)
			(stroke
				(width 0.1524)
				(type default)
			)
			(layer "F.SilkS")
		)
		(fp_poly
			(pts
				(xy -1.778 1.8796) (xy -1.778 -1.8796) (xy 1.778 -1.8796) (xy 1.778 1.8796)
			)
			(stroke
				(width 0)
				(type default)
			)
			(fill no)
			(layer "F.CrtYd")
		)
		(fp_poly
			(pts
				(xy -1.778 1.8796) (xy -1.778 -1.8796) (xy 1.778 -1.8796) (xy 1.778 1.8796)
			)
			(stroke
				(width 0)
				(type default)
			)
			(fill no)
			(layer "F.Fab")
		)
		(pad "D" smd custom
			(at 0 -0.9525 90)
			(size 0.1905 0.1905)
			(layers "F.Cu" "F.Mask" "F.Paste")
			(net "DRV_ACT_20_N")
			(options
				(clearance outline)
				(anchor circle)
			)
			(primitives
				(gr_poly
					(pts
						(arc
							(start -0.1778 0.5715)
							(mid -0.321484 0.511984)
							(end -0.381 0.3683)
						)
						(arc
							(start -0.381 -0.3683)
							(mid -0.321484 -0.511984)
							(end -0.1778 -0.5715)
						)
						(arc
							(start 0.1778 -0.5715)
							(mid 0.321484 -0.511984)
							(end 0.381 -0.3683)
						)
						(arc
							(start 0.381 0.3683)
							(mid 0.321484 0.511984)
							(end 0.1778 0.5715)
						)
					)
					(width 0)
					(fill yes)
				)
			)
		)
		(pad "G" smd custom
			(at -0.98425 0.9525 90)
			(size 0.1905 0.1905)
			(layers "F.Cu" "F.Mask" "F.Paste")
			(net "DRIVE_B_20_ACT")
			(options
				(clearance outline)
				(anchor circle)
			)
			(primitives
				(gr_poly
					(pts
						(arc
							(start -0.1778 0.5715)
							(mid -0.321484 0.511984)
							(end -0.381 0.3683)
						)
						(arc
							(start -0.381 -0.3683)
							(mid -0.321484 -0.511984)
							(end -0.1778 -0.5715)
						)
						(arc
							(start 0.1778 -0.5715)
							(mid 0.321484 -0.511984)
							(end 0.381 -0.3683)
						)
						(arc
							(start 0.381 0.3683)
							(mid 0.321484 0.511984)
							(end 0.1778 0.5715)
						)
					)
					(width 0)
					(fill yes)
				)
			)
		)
		(pad "S" smd custom
			(at 0.98425 0.9525 90)
			(size 0.1905 0.1905)
			(layers "F.Cu" "F.Mask" "F.Paste")
			(net "GND")
			(options
				(clearance outline)
				(anchor circle)
			)
			(primitives
				(gr_poly
					(pts
						(arc
							(start -0.1778 0.5715)
							(mid -0.321484 0.511984)
							(end -0.381 0.3683)
						)
						(arc
							(start -0.381 -0.3683)
							(mid -0.321484 -0.511984)
							(end -0.1778 -0.5715)
						)
						(arc
							(start 0.1778 -0.5715)
							(mid 0.321484 -0.511984)
							(end 0.381 -0.3683)
						)
						(arc
							(start 0.381 0.3683)
							(mid 0.321484 0.511984)
							(end 0.1778 0.5715)
						)
					)
					(width 0)
					(fill yes)
				)
			)
		)
	)
	(footprint ""
		(layer "F.Cu")
		(at 384.734562 -244.660674 -90)
		(property "Reference" "C133"
			(at 0 0 270)
			(layer "F.SilkS")
			(hide yes)
			(effects
				(font
					(size 1.27 1.27)
				)
			)
		)
		(property "Value" "SCD01U16V1KX-GP"
			(at -2.8321 -1.7399 270)
			(unlocked yes)
			(layer "F.Fab")
			(hide yes)
			(effects
				(font
					(size 1.016 1.016)
					(thickness 0.1524)
				)
			)
		)
		(property "Device Type" "C0201H13"
			(at -2.8321 -3.2639 270)
			(unlocked yes)
			(layer "F.Fab")
			(hide yes)
			(effects
				(font
					(size 1.016 1.016)
					(thickness 0.1524)
				)
			)
		)
		(duplicate_pad_numbers_are_jumpers no)
		(fp_rect
			(start -0.2794 0.6477)
			(end 0.2794 -0.6477)
			(stroke
				(width 0)
				(type default)
			)
			(fill no)
			(layer "F.CrtYd")
		)
		(fp_rect
			(start -0.2794 0.6477)
			(end 0.2794 -0.6477)
			(stroke
				(width 0)
				(type default)
			)
			(fill no)
			(layer "F.Fab")
		)
		(pad "1" smd custom
			(at 0 -0.2794 270)
			(size 0.0762 0.0762)
			(layers "F.Cu" "F.Mask" "F.Paste")
			(net "SAS_HDD_RX_P8")
			(options
				(clearance outline)
				(anchor circle)
			)
			(primitives
				(gr_poly
					(pts
						(arc
							(start 0.1524 -0.127)
							(mid 0.137521 -0.162921)
							(end 0.1016 -0.1778)
						)
						(arc
							(start -0.1016 -0.1778)
							(mid -0.137521 -0.162921)
							(end -0.1524 -0.127)
						)
						(arc
							(start -0.1524 0.127)
							(mid -0.137521 0.162921)
							(end -0.1016 0.1778)
						)
						(arc
							(start 0.1016 0.1778)
							(mid 0.137521 0.162921)
							(end 0.1524 0.127)
						)
					)
					(width 0)
					(fill yes)
				)
			)
		)
		(pad "2" smd custom
			(at 0 0.2794 270)
			(size 0.0762 0.0762)
			(layers "F.Cu" "F.Mask" "F.Paste")
			(net "PHY_SCC_B_TO_DRV_B_8_DP")
			(options
				(clearance outline)
				(anchor circle)
			)
			(primitives
				(gr_poly
					(pts
						(arc
							(start 0.1524 -0.127)
							(mid 0.137521 -0.162921)
							(end 0.1016 -0.1778)
						)
						(arc
							(start -0.1016 -0.1778)
							(mid -0.137521 -0.162921)
							(end -0.1524 -0.127)
						)
						(arc
							(start -0.1524 0.127)
							(mid -0.137521 0.162921)
							(end -0.1016 0.1778)
						)
						(arc
							(start 0.1016 0.1778)
							(mid 0.137521 0.162921)
							(end 0.1524 0.127)
						)
					)
					(width 0)
					(fill yes)
				)
			)
		)
	)
	(footprint ""
		(layer "F.Cu")
		(at 144.653 -16.637)
		(property "Reference" "R731"
			(at 0 0 0)
			(layer "F.SilkS")
			(hide yes)
			(effects
				(font
					(size 1.27 1.27)
				)
			)
		)
		(property "Value" "0R2J-2-GP"
			(at 0.064008 -3.993896 0)
			(unlocked yes)
			(layer "F.Fab")
			(hide yes)
			(effects
				(font
					(size 1.016 1.016)
					(thickness 0.1524)
				)
			)
		)
		(property "Device Type" "R402H16"
			(at 0.064008 -5.517896 0)
			(unlocked yes)
			(layer "F.Fab")
			(hide yes)
			(effects
				(font
					(size 1.016 1.016)
					(thickness 0.1524)
				)
			)
		)
		(duplicate_pad_numbers_are_jumpers no)
		(fp_line
			(start -0.508 -0.9398)
			(end -0.508 0.9398)
			(stroke
				(width 0.1524)
				(type default)
			)
			(layer "F.SilkS")
		)
		(fp_line
			(start 0.508 -0.9398)
			(end -0.508 -0.9398)
			(stroke
				(width 0.1524)
				(type default)
			)
			(layer "F.SilkS")
		)
		(fp_rect
			(start -0.508 0.9398)
			(end 0.508 -0.9398)
			(stroke
				(width 0)
				(type default)
			)
			(fill no)
			(layer "F.CrtYd")
		)
		(fp_rect
			(start -0.508 0.9398)
			(end 0.508 -0.9398)
			(stroke
				(width 0)
				(type default)
			)
			(fill no)
			(layer "F.Fab")
		)
		(pad "1" smd custom
			(at 0 -0.4445)
			(size 0.1397 0.1397)
			(layers "F.Cu" "F.Mask" "F.Paste")
			(net "SW_HDD_G28")
			(options
				(clearance outline)
				(anchor circle)
			)
			(primitives
				(gr_poly
					(pts
						(arc
							(start -0.1778 -0.2794)
							(mid -0.249642 -0.249642)
							(end -0.2794 -0.1778)
						)
						(arc
							(start -0.2794 0.1778)
							(mid -0.249642 0.249642)
							(end -0.1778 0.2794)
						)
						(arc
							(start 0.1778 0.2794)
							(mid 0.249642 0.249642)
							(end 0.2794 0.1778)
						)
						(arc
							(start 0.2794 -0.1778)
							(mid 0.249642 -0.249642)
							(end 0.1778 -0.2794)
						)
					)
					(width 0)
					(fill yes)
				)
			)
		)
		(pad "2" smd custom
			(at 0 0.4445)
			(size 0.1397 0.1397)
			(layers "F.Cu" "F.Mask" "F.Paste")
			(net "SW_HDD_R28")
			(options
				(clearance outline)
				(anchor circle)
			)
			(primitives
				(gr_poly
					(pts
						(arc
							(start -0.1778 -0.2794)
							(mid -0.249642 -0.249642)
							(end -0.2794 -0.1778)
						)
						(arc
							(start -0.2794 0.1778)
							(mid -0.249642 0.249642)
							(end -0.1778 0.2794)
						)
						(arc
							(start 0.1778 0.2794)
							(mid 0.249642 0.249642)
							(end 0.2794 0.1778)
						)
						(arc
							(start 0.2794 -0.1778)
							(mid 0.249642 -0.249642)
							(end 0.1778 -0.2794)
						)
					)
					(width 0)
					(fill yes)
				)
			)
		)
	)
)
